(kicad_pcb
	(version 20260206)
	(generator "pcbnew")
	(generator_version "10.0")
	(general
		(thickness 1.6)
		(legacy_teardrops no)
	)
	(paper "A4")
	(title_block
		(title "12092022_DA0F0TYB4D0_F0T_Panel_BD_Front_D_brd_v02_OCP.brd")
		(comment 1 "Grand Teton / footprints 94-98 of 128")
	)
	(layers
		(0 "F.Cu" signal "TOP")
		(4 "In1.Cu" signal "GND")
		(6 "In2.Cu" signal "GND1")
		(2 "B.Cu" signal "BOTTOM")
		(9 "F.Adhes" user "F.Adhesive")
		(11 "B.Adhes" user "B.Adhesive")
		(13 "F.Paste" user "Package Geometry/Pastemask Top")
		(15 "B.Paste" user "Package Geometry/Pastemask Bottom")
		(5 "F.SilkS" user "Ref Des/Silkscreen Top")
		(7 "B.SilkS" user "Ref Des/Silkscreen Bottom")
		(1 "F.Mask" user "Board Geometry/Soldermask Top")
		(3 "B.Mask" user "Board Geometry/Soldermask Bottom")
		(17 "Dwgs.User" user "User.Drawings")
		(19 "Cmts.User" user "User.Comments")
		(21 "Eco1.User" user "User.Eco1")
		(23 "Eco2.User" user "User.Eco2")
		(25 "Edge.Cuts" user "Board Geometry/Outline")
		(27 "Margin" user)
		(31 "F.CrtYd" user "Package Geometry/Place Bound Top")
		(29 "B.CrtYd" user "Package Geometry/Place Bound Bottom")
		(35 "F.Fab" user "Ref Des/Assembly Top")
		(33 "B.Fab" user "Ref Des/Assembly Bottom")
	)
	(footprint ""
		(layer "F.Cu")
		(at 6.100064 -14.899894 180)
		(property "Reference" "H9"
			(at -7.742936 3.361436 0)
			(unlocked yes)
			(layer "F.SilkS")
			(effects
				(font
					(size 0.7874 0.5842)
					(thickness 0.1524)
				)
				(justify left)
			)
		)
		(property "Value" ""
			(at 0 0 180)
			(layer "F.Fab")
			(effects
				(font
					(size 1.27 1.27)
				)
			)
		)
		(duplicate_pad_numbers_are_jumpers no)
		(fp_arc
			(start 1.628648 7.832598)
			(mid -5.048281 6.206014)
			(end -7.999984 0)
			(stroke
				(width 0.1524)
				(type default)
			)
			(layer "F.SilkS")
		)
		(fp_arc
			(start -7.999984 0)
			(mid 3.542385 -7.173048)
			(end 4.863084 6.352286)
			(stroke
				(width 0.1524)
				(type default)
			)
			(layer "F.SilkS")
		)
		(fp_arc
			(start 7.999984 0)
			(mid 6.825974 4.172084)
			(end 3.648456 7.11962)
			(stroke
				(width 0.1524)
				(type default)
			)
			(layer "B.SilkS")
		)
		(fp_arc
			(start -3.65887 7.114286)
			(mid -4.167106 -6.828976)
			(end 7.999984 0)
			(stroke
				(width 0.1524)
				(type default)
			)
			(layer "B.SilkS")
		)
		(fp_circle
			(center 0 0)
			(end -7.999984 0)
			(stroke
				(width 0.1)
				(type default)
			)
			(fill no)
			(layer "B.Fab")
		)
		(fp_circle
			(center 0 0)
			(end -7.999984 0)
			(stroke
				(width 0.1)
				(type default)
			)
			(fill no)
			(layer "F.Fab")
		)
		(pad "" np_thru_hole circle
			(at 0 0 180)
			(size 4.0132 4.0132)
			(drill 4.0132)
			(layers "*.Cu" "*.Mask")
			(clearance 0.381)
			(thermal_gap 0.381)
		)
		(pad "2" thru_hole circle
			(at 3.758692 0 180)
			(size 0.762 0.762)
			(drill 0.5588)
			(layers "*.Cu" "*.Mask")
			(remove_unused_layers no)
			(net "GND")
			(clearance 0.1524)
			(thermal_gap 0.1524)
		)
		(pad "3" thru_hole circle
			(at 2.657602 -2.657602 180)
			(size 0.762 0.762)
			(drill 0.5588)
			(layers "*.Cu" "*.Mask")
			(remove_unused_layers no)
			(net "GND")
			(clearance 0.1524)
			(thermal_gap 0.1524)
		)
		(pad "4" thru_hole circle
			(at 0 -3.758692 180)
			(size 0.762 0.762)
			(drill 0.5588)
			(layers "*.Cu" "*.Mask")
			(remove_unused_layers no)
			(net "GND")
			(clearance 0.1524)
			(thermal_gap 0.1524)
		)
		(pad "5" thru_hole circle
			(at -2.657602 -2.657602 180)
			(size 0.762 0.762)
			(drill 0.5588)
			(layers "*.Cu" "*.Mask")
			(remove_unused_layers no)
			(net "GND")
			(clearance 0.1524)
			(thermal_gap 0.1524)
		)
		(pad "6" thru_hole circle
			(at -3.758692 0 180)
			(size 0.762 0.762)
			(drill 0.5588)
			(layers "*.Cu" "*.Mask")
			(remove_unused_layers no)
			(net "GND")
			(clearance 0.1524)
			(thermal_gap 0.1524)
		)
		(pad "7" thru_hole circle
			(at -2.657602 2.657602 180)
			(size 0.762 0.762)
			(drill 0.5588)
			(layers "*.Cu" "*.Mask")
			(remove_unused_layers no)
			(net "GND")
			(clearance 0.1524)
			(thermal_gap 0.1524)
		)
		(pad "8" thru_hole circle
			(at 0 3.758692 180)
			(size 0.762 0.762)
			(drill 0.5588)
			(layers "*.Cu" "*.Mask")
			(remove_unused_layers no)
			(net "GND")
			(clearance 0.1524)
			(thermal_gap 0.1524)
		)
		(pad "9" thru_hole circle
			(at 2.657602 2.657602 180)
			(size 0.762 0.762)
			(drill 0.5588)
			(layers "*.Cu" "*.Mask")
			(remove_unused_layers no)
			(net "GND")
			(clearance 0.1524)
			(thermal_gap 0.1524)
		)
		(zone
			(layer "F.Cu")
			(hatch none 0.5)
			(connect_pads
				(clearance 0)
			)
			(min_thickness 0.25)
			(keepout
				(tracks not_allowed)
				(vias allowed)
				(pads allowed)
				(copperpour not_allowed)
				(footprints allowed)
			)
			(placement
				(enabled no)
				(sheetname "")
			)
			(fill
				(thermal_gap 0.5)
				(thermal_bridge_width 0.5)
				(island_removal_mode 0)
			)
			(polygon
				(pts
					(arc
						(start 6.100064 -9.645904)
						(mid 0.846074 -14.899894)
						(end 6.100064 -20.153884)
					)
					(arc
						(start 6.100064 -19.925284)
						(mid 1.074674 -14.899894)
						(end 6.100064 -9.874504)
					)
				)
			)
		)
		(zone
			(layer "F.Cu")
			(hatch none 0.5)
			(connect_pads
				(clearance 0)
			)
			(min_thickness 0.25)
			(keepout
				(tracks not_allowed)
				(vias allowed)
				(pads allowed)
				(copperpour not_allowed)
				(footprints allowed)
			)
			(placement
				(enabled no)
				(sheetname "")
			)
			(fill
				(thermal_gap 0.5)
				(thermal_bridge_width 0.5)
				(island_removal_mode 0)
			)
			(polygon
				(pts
					(arc
						(start 6.100064 -9.645904)
						(mid 11.354054 -14.899894)
						(end 6.100064 -20.153884)
					)
					(arc
						(start 6.100064 -19.925284)
						(mid 11.125454 -14.899894)
						(end 6.100064 -9.874504)
					)
				)
			)
		)
		(zone
			(layer "F.Cu")
			(hatch none 0.5)
			(connect_pads
				(clearance 0)
			)
			(min_thickness 0.25)
			(keepout
				(tracks not_allowed)
				(vias allowed)
				(pads allowed)
				(copperpour not_allowed)
				(footprints allowed)
			)
			(placement
				(enabled no)
				(sheetname "")
			)
			(fill
				(thermal_gap 0.5)
				(thermal_bridge_width 0.5)
				(island_removal_mode 0)
			)
			(polygon
				(pts
					(arc
						(start 6.100064 -22.899878)
						(mid -1.89992 -14.899894)
						(end 6.100064 -6.89991)
					)
					(arc
						(start 6.100064 -9.645904)
						(mid 0.764794 -14.981174)
						(end 6.100064 -20.31619)
					)
				)
			)
		)
		(zone
			(layer "F.Cu")
			(hatch none 0.5)
			(connect_pads
				(clearance 0)
			)
			(min_thickness 0.25)
			(keepout
				(tracks not_allowed)
				(vias allowed)
				(pads allowed)
				(copperpour not_allowed)
				(footprints allowed)
			)
			(placement
				(enabled no)
				(sheetname "")
			)
			(fill
				(thermal_gap 0.5)
				(thermal_bridge_width 0.5)
				(island_removal_mode 0)
			)
			(polygon
				(pts
					(arc
						(start 6.100064 -22.899878)
						(mid 14.100048 -14.899894)
						(end 6.100064 -6.89991)
					)
					(arc
						(start 6.100064 -9.645904)
						(mid 11.435334 -14.981174)
						(end 6.100064 -20.31619)
					)
				)
			)
		)
		(zone
			(layers "F.Cu" "B.Cu" "In1.Cu" "In2.Cu")
			(hatch none 0.5)
			(connect_pads
				(clearance 0)
			)
			(min_thickness 0.25)
			(keepout
				(tracks not_allowed)
				(vias allowed)
				(pads allowed)
				(copperpour not_allowed)
				(footprints allowed)
			)
			(placement
				(enabled no)
				(sheetname "")
			)
			(fill
				(thermal_gap 0.5)
				(thermal_bridge_width 0.5)
				(island_removal_mode 0)
			)
			(polygon
				(pts
					(arc
						(start 8.614664 -14.899894)
						(mid 3.585464 -14.899894)
						(end 8.614664 -14.899894)
					)
				)
			)
		)
		(zone
			(layer "B.Cu")
			(hatch none 0.5)
			(connect_pads
				(clearance 0)
			)
			(min_thickness 0.25)
			(keepout
				(tracks not_allowed)
				(vias allowed)
				(pads allowed)
				(copperpour not_allowed)
				(footprints allowed)
			)
			(placement
				(enabled no)
				(sheetname "")
			)
			(fill
				(thermal_gap 0.5)
				(thermal_bridge_width 0.5)
				(island_removal_mode 0)
			)
			(polygon
				(pts
					(arc
						(start 0.592074 -18.400014)
						(mid 2.205327 -22.294751)
						(end 6.100064 -23.908004)
					)
					(arc
						(start 6.100064 -23.425404)
						(mid 2.546577 -21.953501)
						(end 1.074674 -18.400014)
					)
					(arc
						(start 1.074674 -14.899894)
						(mid 2.546577 -11.346407)
						(end 6.100064 -9.874504)
					)
					(arc
						(start 6.100064 -9.391904)
						(mid 2.205327 -11.005157)
						(end 0.592074 -14.899894)
					)
				)
			)
		)
		(zone
			(layer "B.Cu")
			(hatch none 0.5)
			(connect_pads
				(clearance 0)
			)
			(min_thickness 0.25)
			(keepout
				(tracks not_allowed)
				(vias allowed)
				(pads allowed)
				(copperpour not_allowed)
				(footprints allowed)
			)
			(placement
				(enabled no)
				(sheetname "")
			)
			(fill
				(thermal_gap 0.5)
				(thermal_bridge_width 0.5)
				(island_removal_mode 0)
			)
			(polygon
				(pts
					(arc
						(start 11.608054 -18.400014)
						(mid 9.994801 -22.294751)
						(end 6.100064 -23.908004)
					)
					(arc
						(start 6.100064 -23.425404)
						(mid 9.653551 -21.953501)
						(end 11.125454 -18.400014)
					)
					(arc
						(start 11.125454 -14.899894)
						(mid 9.653551 -11.346407)
						(end 6.100064 -9.874504)
					)
					(arc
						(start 6.100064 -9.391904)
						(mid 9.994801 -11.005157)
						(end 11.608054 -14.899894)
					)
				)
			)
		)
	)
	(footprint ""
		(layer "F.Cu")
		(at 96.56953 -23.622 -90)
		(property "Reference" "X2"
			(at 4.59867 0.30353 0)
			(unlocked yes)
			(layer "F.SilkS")
			(effects
				(font
					(size 0.7874 0.5842)
					(thickness 0.1524)
				)
				(justify left)
			)
		)
		(property "Value" ""
			(at 0 0 270)
			(layer "F.Fab")
			(effects
				(font
					(size 1.27 1.27)
				)
			)
		)
		(property "Device Type" "TP_TDR_4P_FTS_MPKT4_H025P0200_IO_TP15_TP_TDR_4P_DIP"
			(at 1.30175 1.27 0)
			(unlocked yes)
			(layer "F.Fab")
			(hide yes)
			(effects
				(font
					(size 0.635 0.4064)
					(thickness 0.1524)
				)
			)
		)
		(property "User Part Number" "TP15"
			(at 1.30175 1.27 0)
			(unlocked yes)
			(layer "Cmts.User")
			(hide yes)
			(effects
				(font
					(size 0.635 0.4064)
					(thickness 0.1524)
				)
			)
		)
		(duplicate_pad_numbers_are_jumpers no)
		(fp_line
			(start 0 3.81)
			(end 2.54 3.81)
			(stroke
				(width 0.1524)
				(type default)
			)
			(layer "F.SilkS")
		)
		(fp_line
			(start 2.54 3.81)
			(end 2.54 3.6703)
			(stroke
				(width 0.1524)
				(type default)
			)
			(layer "F.SilkS")
		)
		(fp_line
			(start 0 3.175)
			(end 0 3.81)
			(stroke
				(width 0.1524)
				(type default)
			)
			(layer "F.SilkS")
		)
		(fp_line
			(start 2.54 1.4097)
			(end 2.54 1.1303)
			(stroke
				(width 0.1524)
				(type default)
			)
			(layer "F.SilkS")
		)
		(fp_line
			(start 0 0.635)
			(end 0 1.905)
			(stroke
				(width 0.1524)
				(type default)
			)
			(layer "F.SilkS")
		)
		(fp_line
			(start 2.54 -1.1303)
			(end 2.54 -1.27)
			(stroke
				(width 0.1524)
				(type default)
			)
			(layer "F.SilkS")
		)
		(fp_line
			(start 0 -1.27)
			(end 0 -0.635)
			(stroke
				(width 0.1524)
				(type default)
			)
			(layer "F.SilkS")
		)
		(fp_line
			(start 2.54 -1.27)
			(end 0 -1.27)
			(stroke
				(width 0.1524)
				(type default)
			)
			(layer "F.SilkS")
		)
		(fp_poly
			(pts
				(xy -0.761746 0) (xy -2.285746 -0.762) (xy -2.285746 0.762)
			)
			(stroke
				(width 0)
				(type default)
			)
			(fill yes)
			(layer "F.SilkS")
		)
		(fp_line
			(start 0 3.81)
			(end 2.54 3.81)
			(stroke
				(width 0.1)
				(type default)
			)
			(layer "F.Fab")
		)
		(fp_line
			(start 2.54 3.81)
			(end 2.54 -1.27)
			(stroke
				(width 0.1)
				(type default)
			)
			(layer "F.Fab")
		)
		(fp_line
			(start 0 -1.27)
			(end 0 3.81)
			(stroke
				(width 0.1)
				(type default)
			)
			(layer "F.Fab")
		)
		(fp_line
			(start 2.54 -1.27)
			(end 0 -1.27)
			(stroke
				(width 0.1)
				(type default)
			)
			(layer "F.Fab")
		)
		(fp_poly
			(pts
				(xy -0.761746 0) (xy -2.285746 -0.762) (xy -2.285746 0.762)
			)
			(stroke
				(width 0)
				(type default)
			)
			(fill yes)
			(layer "F.Fab")
		)
		(pad "1" thru_hole circle
			(at 0 0 270)
			(size 1.0033 1.0033)
			(drill 0.249936)
			(layers "*.Cu" "*.Mask")
			(remove_unused_layers no)
			(net "TDR_DIFF_85_TOP_DN")
			(clearance 0.10795)
			(thermal_gap 0.10795)
			(padstack
				(mode front_inner_back)
				(layer "Inner"
					(shape circle)
					(size 0.8001 0.8001)
					(clearance 0.1524)
				)
				(layer "B.Cu"
					(shape circle)
					(size 1.0033 1.0033)
					(clearance 0.10795)
				)
			)
		)
		(pad "2" thru_hole circle
			(at 2.54 0 270)
			(size 1.9939 1.9939)
			(drill 0.249936)
			(layers "*.Cu" "*.Mask")
			(remove_unused_layers no)
			(net "GND_TDR")
			(clearance 0.10795)
			(thermal_gap 0.10795)
			(padstack
				(mode front_inner_back)
				(layer "Inner"
					(shape circle)
					(size 0.8001 0.8001)
					(clearance 0.1524)
				)
				(layer "B.Cu"
					(shape circle)
					(size 1.9939 1.9939)
					(clearance 0.10795)
				)
			)
		)
		(pad "3" thru_hole circle
			(at 2.54 2.54 270)
			(size 1.9939 1.9939)
			(drill 0.249936)
			(layers "*.Cu" "*.Mask")
			(remove_unused_layers no)
			(net "GND_TDR")
			(clearance 0.10795)
			(thermal_gap 0.10795)
			(padstack
				(mode front_inner_back)
				(layer "Inner"
					(shape circle)
					(size 0.8001 0.8001)
					(clearance 0.1524)
				)
				(layer "B.Cu"
					(shape circle)
					(size 1.9939 1.9939)
					(clearance 0.10795)
				)
			)
		)
		(pad "4" thru_hole circle
			(at 0 2.54 270)
			(size 1.0033 1.0033)
			(drill 0.249936)
			(layers "*.Cu" "*.Mask")
			(remove_unused_layers no)
			(net "TDR_DIFF_85_TOP_DP")
			(clearance 0.10795)
			(thermal_gap 0.10795)
			(padstack
				(mode front_inner_back)
				(layer "Inner"
					(shape circle)
					(size 0.8001 0.8001)
					(clearance 0.1524)
				)
				(layer "B.Cu"
					(shape circle)
					(size 1.0033 1.0033)
					(clearance 0.10795)
				)
			)
		)
	)
	(footprint ""
		(layer "F.Cu")
		(at 34.040064 -37.573712)
		(property "Reference" "H3"
			(at 0.707136 -3.026918 0)
			(unlocked yes)
			(layer "F.SilkS")
			(effects
				(font
					(size 0.7874 0.5842)
					(thickness 0.1524)
				)
				(justify left)
			)
		)
		(property "Value" ""
			(at 0 0 0)
			(layer "F.Fab")
			(effects
				(font
					(size 1.27 1.27)
				)
			)
		)
		(duplicate_pad_numbers_are_jumpers no)
		(fp_circle
			(center 0 0)
			(end 2.4003 0)
			(stroke
				(width 0.1524)
				(type default)
			)
			(fill no)
			(layer "F.SilkS")
		)
		(fp_circle
			(center 0 0)
			(end 6.5913 0)
			(stroke
				(width 0.1524)
				(type default)
			)
			(fill no)
			(layer "B.SilkS")
		)
		(fp_circle
			(center 0 0)
			(end 6.5913 0)
			(stroke
				(width 0.1)
				(type default)
			)
			(fill no)
			(layer "B.Fab")
		)
		(fp_circle
			(center 0 0)
			(end 2.4003 0)
			(stroke
				(width 0.1)
				(type default)
			)
			(fill no)
			(layer "F.Fab")
		)
		(pad "" np_thru_hole circle
			(at 0 0)
			(size 3.175 3.175)
			(drill 3.175)
			(layers "*.Cu" "*.Mask")
			(clearance 0.381)
			(thermal_gap 0.381)
		)
		(zone
			(layers "F.Cu" "B.Cu" "In1.Cu" "In2.Cu")
			(hatch none 0.5)
			(connect_pads
				(clearance 0)
			)
			(min_thickness 0.25)
			(keepout
				(tracks not_allowed)
				(vias allowed)
				(pads allowed)
				(copperpour not_allowed)
				(footprints allowed)
			)
			(placement
				(enabled no)
				(sheetname "")
			)
			(fill
				(thermal_gap 0.5)
				(thermal_bridge_width 0.5)
				(island_removal_mode 0)
			)
			(polygon
				(pts
					(arc
						(start 36.135564 -37.573712)
						(mid 31.944564 -37.573712)
						(end 36.135564 -37.573712)
					)
				)
			)
		)
	)
	(footprint ""
		(layer "F.Cu")
		(at 19.558 -23.114)
		(property "Reference" "R36"
			(at 0.381 -4.16433 0)
			(unlocked yes)
			(layer "F.SilkS")
			(effects
				(font
					(size 0.7874 0.5842)
					(thickness 0.1524)
				)
			)
		)
		(property "Value" ""
			(at 0 0 0)
			(layer "F.Fab")
			(effects
				(font
					(size 1.27 1.27)
				)
			)
		)
		(duplicate_pad_numbers_are_jumpers no)
		(fp_line
			(start -0.7874 -0.4064)
			(end 0.7874 -0.4064)
			(stroke
				(width 0.1524)
				(type default)
			)
			(layer "F.SilkS")
		)
		(fp_line
			(start -0.7874 0.4064)
			(end -0.7874 -0.4064)
			(stroke
				(width 0.1524)
				(type default)
			)
			(layer "F.SilkS")
		)
		(fp_line
			(start 0.7874 -0.4064)
			(end 0.7874 0.4064)
			(stroke
				(width 0.1524)
				(type default)
			)
			(layer "F.SilkS")
		)
		(fp_line
			(start 0.7874 0.4064)
			(end -0.7874 0.4064)
			(stroke
				(width 0.1524)
				(type default)
			)
			(layer "F.SilkS")
		)
		(fp_line
			(start -0.67945 -0.305054)
			(end -0.12065 -0.305054)
			(stroke
				(width 0.1)
				(type default)
			)
			(layer "F.Fab")
		)
		(fp_line
			(start -0.67945 0.3048)
			(end -0.67945 -0.305054)
			(stroke
				(width 0.1)
				(type default)
			)
			(layer "F.Fab")
		)
		(fp_line
			(start -0.12065 -0.305054)
			(end -0.12065 -0.2794)
			(stroke
				(width 0.1)
				(type default)
			)
			(layer "F.Fab")
		)
		(fp_line
			(start -0.12065 -0.2794)
			(end 0.12065 -0.2794)
			(stroke
				(width 0.1)
				(type default)
			)
			(layer "F.Fab")
		)
		(fp_line
			(start -0.12065 0.2794)
			(end -0.12065 0.3048)
			(stroke
				(width 0.1)
				(type default)
			)
			(layer "F.Fab")
		)
		(fp_line
			(start -0.12065 0.3048)
			(end -0.67945 0.3048)
			(stroke
				(width 0.1)
				(type default)
			)
			(layer "F.Fab")
		)
		(fp_line
			(start 0.120396 0.2794)
			(end -0.12065 0.2794)
			(stroke
				(width 0.1)
				(type default)
			)
			(layer "F.Fab")
		)
		(fp_line
			(start 0.120396 0.3048)
			(end 0.120396 0.2794)
			(stroke
				(width 0.1)
				(type default)
			)
			(layer "F.Fab")
		)
		(fp_line
			(start 0.12065 -0.3048)
			(end 0.67945 -0.3048)
			(stroke
				(width 0.1)
				(type default)
			)
			(layer "F.Fab")
		)
		(fp_line
			(start 0.12065 -0.2794)
			(end 0.12065 -0.3048)
			(stroke
				(width 0.1)
				(type default)
			)
			(layer "F.Fab")
		)
		(fp_line
			(start 0.67945 -0.3048)
			(end 0.67945 0.3048)
			(stroke
				(width 0.1)
				(type default)
			)
			(layer "F.Fab")
		)
		(fp_line
			(start 0.67945 0.3048)
			(end 0.120396 0.3048)
			(stroke
				(width 0.1)
				(type default)
			)
			(layer "F.Fab")
		)
		(pad "1" smd circle
			(at -0.40005 0)
			(size 0 0)
			(layers "F.Cu" "F.Mask" "F.Paste")
			(net "SMB_SCL")
		)
		(pad "2" smd circle
			(at 0.40005 0)
			(size 0 0)
			(layers "F.Cu" "F.Mask" "F.Paste")
			(net "SMB_TMP75_SCL")
		)
	)
	(footprint ""
		(layer "F.Cu")
		(at 3.556 -64.897)
		(property "Reference" "H4"
			(at -2.54 -2.76733 0)
			(unlocked yes)
			(layer "F.SilkS")
			(effects
				(font
					(size 0.7874 0.5842)
					(thickness 0.1524)
				)
				(justify left)
			)
		)
		(property "Value" ""
			(at 0 0 0)
			(layer "F.Fab")
			(effects
				(font
					(size 1.27 1.27)
				)
			)
		)
		(duplicate_pad_numbers_are_jumpers no)
		(fp_circle
			(center 0 0)
			(end 2.4003 0)
			(stroke
				(width 0.1524)
				(type default)
			)
			(fill no)
			(layer "F.SilkS")
		)
		(fp_arc
			(start 5.969762 -2.794254)
			(mid 6.434026 -1.43127)
			(end 6.5913 0)
			(stroke
				(width 0.1524)
				(type default)
			)
			(layer "B.SilkS")
		)
		(fp_arc
			(start 6.5913 0)
			(mid -4.141127 5.129364)
			(end -1.389634 -6.443218)
			(stroke
				(width 0.1524)
				(type default)
			)
			(layer "B.SilkS")
		)
		(fp_circle
			(center 0 0)
			(end 6.5913 0)
			(stroke
				(width 0.1)
				(type default)
			)
			(fill no)
			(layer "B.Fab")
		)
		(fp_circle
			(center 0 0)
			(end 2.4003 0)
			(stroke
				(width 0.1)
				(type default)
			)
			(fill no)
			(layer "F.Fab")
		)
		(pad "" np_thru_hole circle
			(at 0 0)
			(size 3.175 3.175)
			(drill 3.175)
			(layers "*.Cu" "*.Mask")
			(clearance 0.381)
			(thermal_gap 0.381)
		)
		(zone
			(layers "F.Cu" "B.Cu" "In1.Cu" "In2.Cu")
			(hatch none 0.5)
			(connect_pads
				(clearance 0)
			)
			(min_thickness 0.25)
			(keepout
				(tracks not_allowed)
				(vias allowed)
				(pads allowed)
				(copperpour not_allowed)
				(footprints allowed)
			)
			(placement
				(enabled no)
				(sheetname "")
			)
			(fill
				(thermal_gap 0.5)
				(thermal_bridge_width 0.5)
				(island_removal_mode 0)
			)
			(polygon
				(pts
					(arc
						(start 5.6515 -64.897)
						(mid 1.4605 -64.897)
						(end 5.6515 -64.897)
					)
				)
			)
		)
	)
)
